(kicad_sch
	(version 20250114)
	(generator "eeschema")
	(generator_version "9.0")
	(paper "A3")
	(title_block
		(title "COM Express 7 Baseboard")
		(date "2025-02-04")
		(rev "1.1.2")
		(company "Antmicro Ltd")
		(comment 1 "www.antmicro.com")
	)
	(bus_alias "10GBaseKR"
		(members "TX+" "TX-" "RX+" "RX-")
	)
	(bus_alias "GbE"
		(members "MDI3+" "MDI3-" "MDI2+" "MDI2-" "MDI1+" "MDI1-" "MDI0+" "MDI0-"
			"CTREF"
		)
	)
	(bus_alias "MDIO"
		(members "MDIO" "MDC")
	)
	(bus_alias "PCIe"
		(members "TX7+" "TX7-" "TX6+" "TX6-" "TX5+" "TX5-" "TX4+" "TX4-" "TX3+"
			"TX3-" "TX2+" "TX2-" "TX1+" "TX1-" "TX0+" "TX0-" "RX7+" "RX7-" "RX6+"
			"RX6-" "RX5+" "RX5-" "RX4+" "RX4-" "RX3+" "RX3-" "RX2+" "RX2-" "RX1+"
			"RX1-" "RX0+" "RX0-"
		)
	)
	(bus_alias "USB"
		(members "D+" "D-")
	)
	(bus_alias "USBSS"
		(members "TX+" "TX-" "RX+" "RX-")
	)
	(junction
		(at 325.12 66.04)
		(diameter 0)
		(color 0 0 0 0)
	)
	(junction
		(at 327.66 139.7)
		(diameter 0)
		(color 0 0 0 0)
	)
	(junction
		(at 121.92 86.36)
		(diameter 0)
		(color 0 0 0 0)
	)
	(junction
		(at 274.32 236.22)
		(diameter 0)
		(color 0 0 0 0)
	)
	(junction
		(at 62.23 238.76)
		(diameter 0)
		(color 0 0 0 0)
	)
	(junction
		(at 46.99 149.86)
		(diameter 0)
		(color 0 0 0 0)
	)
	(junction
		(at 327.66 218.44)
		(diameter 0)
		(color 0 0 0 0)
	)
	(junction
		(at 46.99 171.45)
		(diameter 0)
		(color 0 0 0 0)
	)
	(junction
		(at 327.66 104.14)
		(diameter 0)
		(color 0 0 0 0)
	)
	(junction
		(at 330.2 213.36)
		(diameter 0)
		(color 0 0 0 0)
	)
	(junction
		(at 325.12 101.6)
		(diameter 0)
		(color 0 0 0 0)
	)
	(junction
		(at 142.24 208.28)
		(diameter 0)
		(color 0 0 0 0)
	)
	(junction
		(at 121.92 127)
		(diameter 0)
		(color 0 0 0 0)
	)
	(junction
		(at 62.23 127)
		(diameter 0)
		(color 0 0 0 0)
	)
	(junction
		(at 259.08 238.76)
		(diameter 0)
		(color 0 0 0 0)
	)
	(junction
		(at 327.66 68.58)
		(diameter 0)
		(color 0 0 0 0)
	)
	(junction
		(at 256.54 241.3)
		(diameter 0)
		(color 0 0 0 0)
	)
	(junction
		(at 62.23 144.78)
		(diameter 0)
		(color 0 0 0 0)
	)
	(bus
		(pts
			(xy 259.08 213.36) (xy 281.94 213.36)
		)
		(stroke
			(width 0)
			(type default)
			(color 255 153 0 1)
		)
	)
	(wire
		(pts
			(xy 248.92 222.25) (xy 274.32 222.25)
		)
		(stroke
			(width 0)
			(type default)
		)
	)
	(bus
		(pts
			(xy 299.72 30.48) (xy 342.9 30.48)
		)
		(stroke
			(width 0)
			(type default)
		)
	)
	(wire
		(pts
			(xy 121.92 88.9) (xy 121.92 86.36)
		)
		(stroke
			(width 0)
			(type default)
		)
	)
	(wire
		(pts
			(xy 325.12 66.04) (xy 322.58 66.04)
		)
		(stroke
			(width 0)
			(type default)
		)
	)
	(bus
		(pts
			(xy 248.92 142.24) (xy 281.94 142.24)
		)
		(stroke
			(width 0)
			(type default)
			(color 0 0 255 1)
		)
	)
	(bus
		(pts
			(xy 256.54 241.3) (xy 266.7 241.3)
		)
		(stroke
			(width 0)
			(type default)
		)
	)
	(bus
		(pts
			(xy 119.38 76.2) (xy 162.56 76.2)
		)
		(stroke
			(width 0)
			(type default)
			(color 0 255 255 1)
		)
	)
	(wire
		(pts
			(xy 340.36 106.68) (xy 340.36 33.02)
		)
		(stroke
			(width 0)
			(type default)
		)
	)
	(wire
		(pts
			(xy 248.92 227.33) (xy 259.08 227.33)
		)
		(stroke
			(width 0)
			(type default)
		)
	)
	(wire
		(pts
			(xy 355.6 142.24) (xy 355.6 27.94)
		)
		(stroke
			(width 0)
			(type default)
		)
	)
	(bus
		(pts
			(xy 119.38 60.96) (xy 162.56 60.96)
		)
		(stroke
			(width 0)
			(type default)
		)
	)
	(wire
		(pts
			(xy 322.58 106.68) (xy 340.36 106.68)
		)
		(stroke
			(width 0)
			(type default)
		)
	)
	(bus
		(pts
			(xy 248.92 166.37) (xy 273.05 166.37)
		)
		(stroke
			(width 0)
			(type default)
		)
	)
	(bus
		(pts
			(xy 119.38 109.22) (xy 162.56 109.22)
		)
		(stroke
			(width 0)
			(type default)
			(color 255 0 0 1)
		)
	)
	(wire
		(pts
			(xy 279.4 241.3) (xy 332.74 241.3)
		)
		(stroke
			(width 0)
			(type default)
		)
	)
	(wire
		(pts
			(xy 119.38 68.58) (xy 162.56 68.58)
		)
		(stroke
			(width 0)
			(type default)
		)
	)
	(bus
		(pts
			(xy 78.74 147.32) (xy 44.45 147.32)
		)
		(stroke
			(width 0)
			(type default)
		)
	)
	(bus
		(pts
			(xy 78.74 152.4) (xy 67.31 152.4)
		)
		(stroke
			(width 0)
			(type default)
		)
	)
	(wire
		(pts
			(xy 62.23 46.99) (xy 62.23 127)
		)
		(stroke
			(width 0)
			(type default)
		)
	)
	(bus
		(pts
			(xy 142.24 208.28) (xy 142.24 215.9)
		)
		(stroke
			(width 0)
			(type default)
		)
	)
	(wire
		(pts
			(xy 46.99 171.45) (xy 46.99 228.6)
		)
		(stroke
			(width 0)
			(type default)
		)
	)
	(bus
		(pts
			(xy 335.28 73.66) (xy 335.28 35.56)
		)
		(stroke
			(width 0)
			(type default)
		)
	)
	(wire
		(pts
			(xy 78.74 66.04) (xy 53.34 66.04)
		)
		(stroke
			(width 0)
			(type default)
		)
	)
	(bus
		(pts
			(xy 322.58 144.78) (xy 358.14 144.78)
		)
		(stroke
			(width 0)
			(type default)
		)
	)
	(wire
		(pts
			(xy 325.12 101.6) (xy 325.12 137.16)
		)
		(stroke
			(width 0)
			(type default)
		)
	)
	(wire
		(pts
			(xy 281.94 173.99) (xy 270.51 173.99)
		)
		(stroke
			(width 0)
			(type default)
		)
	)
	(wire
		(pts
			(xy 66.04 218.44) (xy 66.04 261.62)
		)
		(stroke
			(width 0)
			(type default)
		)
	)
	(bus
		(pts
			(xy 358.14 144.78) (xy 358.14 25.4)
		)
		(stroke
			(width 0)
			(type default)
		)
	)
	(bus
		(pts
			(xy 154.94 241.3) (xy 154.94 246.38)
		)
		(stroke
			(width 0)
			(type default)
		)
	)
	(wire
		(pts
			(xy 46.99 171.45) (xy 123.19 171.45)
		)
		(stroke
			(width 0)
			(type default)
		)
	)
	(bus
		(pts
			(xy 259.08 195.58) (xy 259.08 213.36)
		)
		(stroke
			(width 0)
			(type default)
			(color 255 153 0 1)
		)
	)
	(bus
		(pts
			(xy 266.7 205.74) (xy 281.94 205.74)
		)
		(stroke
			(width 0)
			(type default)
			(color 0 0 255 1)
		)
	)
	(wire
		(pts
			(xy 55.88 226.06) (xy 78.74 226.06)
		)
		(stroke
			(width 0)
			(type default)
		)
	)
	(wire
		(pts
			(xy 71.12 220.98) (xy 71.12 256.54)
		)
		(stroke
			(width 0)
			(type default)
		)
	)
	(wire
		(pts
			(xy 46.99 228.6) (xy 78.74 228.6)
		)
		(stroke
			(width 0)
			(type default)
		)
	)
	(bus
		(pts
			(xy 342.9 109.22) (xy 342.9 30.48)
		)
		(stroke
			(width 0)
			(type default)
		)
	)
	(bus
		(pts
			(xy 119.38 116.84) (xy 162.56 116.84)
		)
		(stroke
			(width 0)
			(type default)
		)
	)
	(wire
		(pts
			(xy 270.51 173.99) (xy 270.51 168.91)
		)
		(stroke
			(width 0)
			(type default)
		)
	)
	(wire
		(pts
			(xy 121.92 86.36) (xy 162.56 86.36)
		)
		(stroke
			(width 0)
			(type default)
		)
	)
	(bus
		(pts
			(xy 322.58 109.22) (xy 342.9 109.22)
		)
		(stroke
			(width 0)
			(type default)
		)
	)
	(bus
		(pts
			(xy 119.38 73.66) (xy 162.56 73.66)
		)
		(stroke
			(width 0)
			(type default)
			(color 0 0 255 1)
		)
	)
	(wire
		(pts
			(xy 327.66 68.58) (xy 327.66 104.14)
		)
		(stroke
			(width 0)
			(type default)
		)
	)
	(wire
		(pts
			(xy 322.58 218.44) (xy 327.66 218.44)
		)
		(stroke
			(width 0)
			(type default)
		)
	)
	(wire
		(pts
			(xy 279.4 278.13) (xy 279.4 241.3)
		)
		(stroke
			(width 0)
			(type default)
		)
	)
	(wire
		(pts
			(xy 322.58 213.36) (xy 330.2 213.36)
		)
		(stroke
			(width 0)
			(type default)
		)
	)
	(bus
		(pts
			(xy 248.92 195.58) (xy 259.08 195.58)
		)
		(stroke
			(width 0)
			(type default)
			(color 255 153 0 1)
		)
	)
	(wire
		(pts
			(xy 144.78 251.46) (xy 157.48 251.46)
		)
		(stroke
			(width 0)
			(type default)
		)
	)
	(wire
		(pts
			(xy 46.99 171.45) (xy 46.99 149.86)
		)
		(stroke
			(width 0)
			(type default)
		)
	)
	(wire
		(pts
			(xy 340.36 33.02) (xy 299.72 33.02)
		)
		(stroke
			(width 0)
			(type default)
		)
	)
	(bus
		(pts
			(xy 254 246.38) (xy 256.54 246.38)
		)
		(stroke
			(width 0)
			(type default)
		)
	)
	(wire
		(pts
			(xy 322.58 142.24) (xy 355.6 142.24)
		)
		(stroke
			(width 0)
			(type default)
		)
	)
	(wire
		(pts
			(xy 119.38 114.3) (xy 162.56 114.3)
		)
		(stroke
			(width 0)
			(type default)
		)
	)
	(wire
		(pts
			(xy 322.58 68.58) (xy 327.66 68.58)
		)
		(stroke
			(width 0)
			(type default)
		)
	)
	(bus
		(pts
			(xy 248.92 58.42) (xy 254 58.42)
		)
		(stroke
			(width 0)
			(type default)
		)
	)
	(wire
		(pts
			(xy 119.38 111.76) (xy 162.56 111.76)
		)
		(stroke
			(width 0)
			(type default)
		)
	)
	(wire
		(pts
			(xy 205.74 238.76) (xy 259.08 238.76)
		)
		(stroke
			(width 0)
			(type default)
		)
	)
	(wire
		(pts
			(xy 332.74 241.3) (xy 332.74 220.98)
		)
		(stroke
			(width 0)
			(type default)
		)
	)
	(wire
		(pts
			(xy 62.23 144.78) (xy 62.23 238.76)
		)
		(stroke
			(width 0)
			(type default)
		)
	)
	(wire
		(pts
			(xy 119.38 86.36) (xy 121.92 86.36)
		)
		(stroke
			(width 0)
			(type default)
		)
	)
	(wire
		(pts
			(xy 276.86 238.76) (xy 330.2 238.76)
		)
		(stroke
			(width 0)
			(type default)
		)
	)
	(wire
		(pts
			(xy 198.12 246.38) (xy 205.74 246.38)
		)
		(stroke
			(width 0)
			(type default)
		)
	)
	(bus
		(pts
			(xy 299.72 35.56) (xy 335.28 35.56)
		)
		(stroke
			(width 0)
			(type default)
		)
	)
	(wire
		(pts
			(xy 123.19 165.1) (xy 127 165.1)
		)
		(stroke
			(width 0)
			(type default)
		)
	)
	(wire
		(pts
			(xy 62.23 127) (xy 62.23 144.78)
		)
		(stroke
			(width 0)
			(type default)
		)
	)
	(wire
		(pts
			(xy 332.74 71.12) (xy 332.74 38.1)
		)
		(stroke
			(width 0)
			(type default)
		)
	)
	(wire
		(pts
			(xy 325.12 137.16) (xy 322.58 137.16)
		)
		(stroke
			(width 0)
			(type default)
		)
	)
	(wire
		(pts
			(xy 261.62 251.46) (xy 261.62 224.79)
		)
		(stroke
			(width 0)
			(type default)
		)
	)
	(wire
		(pts
			(xy 62.23 144.78) (xy 78.74 144.78)
		)
		(stroke
			(width 0)
			(type default)
		)
	)
	(bus
		(pts
			(xy 248.92 180.34) (xy 264.16 180.34)
		)
		(stroke
			(width 0)
			(type default)
			(color 194 0 194 1)
		)
	)
	(bus
		(pts
			(xy 299.72 20.32) (xy 365.76 20.32)
		)
		(stroke
			(width 0)
			(type default)
		)
	)
	(wire
		(pts
			(xy 332.74 38.1) (xy 299.72 38.1)
		)
		(stroke
			(width 0)
			(type default)
		)
	)
	(wire
		(pts
			(xy 55.88 68.58) (xy 55.88 226.06)
		)
		(stroke
			(width 0)
			(type default)
		)
	)
	(wire
		(pts
			(xy 157.48 248.92) (xy 147.32 248.92)
		)
		(stroke
			(width 0)
			(type default)
		)
	)
	(wire
		(pts
			(xy 46.99 149.86) (xy 46.99 25.4)
		)
		(stroke
			(width 0)
			(type default)
		)
	)
	(bus
		(pts
			(xy 266.7 219.71) (xy 266.7 241.3)
		)
		(stroke
			(width 0)
			(type default)
		)
	)
	(bus
		(pts
			(xy 119.38 81.28) (xy 162.56 81.28)
		)
		(stroke
			(width 0)
			(type default)
			(color 0 0 255 1)
		)
	)
	(wire
		(pts
			(xy 274.32 222.25) (xy 274.32 236.22)
		)
		(stroke
			(width 0)
			(type default)
		)
	)
	(wire
		(pts
			(xy 76.2 233.68) (xy 76.2 275.59)
		)
		(stroke
			(width 0)
			(type default)
		)
	)
	(wire
		(pts
			(xy 276.86 275.59) (xy 276.86 238.76)
		)
		(stroke
			(width 0)
			(type default)
		)
	)
	(wire
		(pts
			(xy 327.66 46.99) (xy 62.23 46.99)
		)
		(stroke
			(width 0)
			(type default)
		)
	)
	(bus
		(pts
			(xy 264.16 180.34) (xy 264.16 208.28)
		)
		(stroke
			(width 0)
			(type default)
			(color 194 0 194 1)
		)
	)
	(wire
		(pts
			(xy 322.58 139.7) (xy 327.66 139.7)
		)
		(stroke
			(width 0)
			(type default)
		)
	)
	(bus
		(pts
			(xy 322.58 215.9) (xy 365.76 215.9)
		)
		(stroke
			(width 0)
			(type default)
		)
	)
	(bus
		(pts
			(xy 119.38 83.82) (xy 162.56 83.82)
		)
		(stroke
			(width 0)
			(type default)
			(color 0 255 255 1)
		)
	)
	(bus
		(pts
			(xy 248.92 101.6) (xy 281.94 101.6)
		)
		(stroke
			(width 0)
			(type default)
			(color 194 0 194 1)
		)
	)
	(wire
		(pts
			(xy 299.72 41.91) (xy 325.12 41.91)
		)
		(stroke
			(width 0)
			(type default)
		)
	)
	(wire
		(pts
			(xy 66.04 261.62) (xy 157.48 261.62)
		)
		(stroke
			(width 0)
			(type default)
		)
	)
	(wire
		(pts
			(xy 322.58 101.6) (xy 325.12 101.6)
		)
		(stroke
			(width 0)
			(type default)
		)
	)
	(bus
		(pts
			(xy 157.48 246.38) (xy 154.94 246.38)
		)
		(stroke
			(width 0)
			(type default)
		)
	)
	(bus
		(pts
			(xy 154.94 144.78) (xy 162.56 144.78)
		)
		(stroke
			(width 0)
			(type default)
			(color 194 0 194 1)
		)
	)
	(bus
		(pts
			(xy 44.45 22.86) (xy 44.45 147.32)
		)
		(stroke
			(width 0)
			(type default)
		)
	)
	(bus
		(pts
			(xy 162.56 195.58) (xy 137.16 195.58)
		)
		(stroke
			(width 0)
			(type default)
			(color 255 153 0 1)
		)
	)
	(bus
		(pts
			(xy 119.38 119.38) (xy 162.56 119.38)
		)
		(stroke
			(width 0)
			(type default)
		)
	)
	(wire
		(pts
			(xy 123.19 171.45) (xy 123.19 165.1)
		)
		(stroke
			(width 0)
			(type default)
		)
	)
	(bus
		(pts
			(xy 119.38 215.9) (xy 142.24 215.9)
		)
		(stroke
			(width 0)
			(type default)
		)
	)
	(bus
		(pts
			(xy 67.31 152.4) (xy 67.31 208.28)
		)
		(stroke
			(width 0)
			(type default)
		)
	)
	(wire
		(pts
			(xy 73.66 231.14) (xy 78.74 231.14)
		)
		(stroke
			(width 0)
			(type default)
		)
	)
	(wire
		(pts
			(xy 119.38 127) (xy 121.92 127)
		)
		(stroke
			(width 0)
			(type default)
		)
	)
	(bus
		(pts
			(xy 137.16 195.58) (xy 137.16 180.34)
		)
		(stroke
			(width 0)
			(type default)
			(color 255 153 0 1)
		)
	)
	(wire
		(pts
			(xy 121.92 129.54) (xy 121.92 127)
		)
		(stroke
			(width 0)
			(type default)
		)
	)
	(wire
		(pts
			(xy 327.66 236.22) (xy 327.66 218.44)
		)
		(stroke
			(width 0)
			(type default)
		)
	)
	(bus
		(pts
			(xy 299.72 25.4) (xy 358.14 25.4)
		)
		(stroke
			(width 0)
			(type default)
		)
	)
	(wire
		(pts
			(xy 157.48 259.08) (xy 68.58 259.08)
		)
		(stroke
			(width 0)
			(type default)
		)
	)
	(wire
		(pts
			(xy 53.34 66.04) (xy 53.34 223.52)
		)
		(stroke
			(width 0)
			(type default)
		)
	)
	(wire
		(pts
			(xy 274.32 236.22) (xy 327.66 236.22)
		)
		(stroke
			(width 0)
			(type default)
		)
	)
	(bus
		(pts
			(xy 119.38 144.78) (xy 127 144.78)
		)
		(stroke
			(width 0)
			(type default)
			(color 194 0 194 1)
		)
	)
	(wire
		(pts
			(xy 119.38 129.54) (xy 121.92 129.54)
		)
		(stroke
			(width 0)
			(type default)
		)
	)
	(bus
		(pts
			(xy 365.76 20.32) (xy 365.76 215.9)
		)
		(stroke
			(width 0)
			(type default)
		)
	)
	(bus
		(pts
			(xy 76.2 135.89) (xy 162.56 135.89)
		)
		(stroke
			(width 0)
			(type default)
		)
	)
	(wire
		(pts
			(xy 330.2 238.76) (xy 330.2 213.36)
		)
		(stroke
			(width 0)
			(type default)
		)
	)
	(bus
		(pts
			(xy 154.94 241.3) (xy 256.54 241.3)
		)
		(stroke
			(width 0)
			(type default)
		)
	)
	(bus
		(pts
			(xy 76.2 129.54) (xy 76.2 135.89)
		)
		(stroke
			(width 0)
			(type default)
		)
	)
	(bus
		(pts
			(xy 273.05 166.37) (xy 273.05 171.45)
		)
		(stroke
			(width 0)
			(type default)
		)
	)
	(wire
		(pts
			(xy 274.32 254) (xy 274.32 236.22)
		)
		(stroke
			(width 0)
			(type default)
		)
	)
	(wire
		(pts
			(xy 327.66 68.58) (xy 327.66 46.99)
		)
		(stroke
			(width 0)
			(type default)
		)
	)
	(wire
		(pts
			(xy 73.66 231.14) (xy 73.66 278.13)
		)
		(stroke
			(width 0)
			(type default)
		)
	)
	(wire
		(pts
			(xy 330.2 213.36) (xy 363.22 213.36)
		)
		(stroke
			(width 0)
			(type default)
		)
	)
	(bus
		(pts
			(xy 142.24 208.28) (xy 162.56 208.28)
		)
		(stroke
			(width 0)
			(type default)
		)
	)
	(wire
		(pts
			(xy 157.48 256.54) (xy 71.12 256.54)
		)
		(stroke
			(width 0)
			(type default)
		)
	)
	(wire
		(pts
			(xy 327.66 139.7) (xy 327.66 104.14)
		)
		(stroke
			(width 0)
			(type default)
		)
	)
	(wire
		(pts
			(xy 261.62 224.79) (xy 248.92 224.79)
		)
		(stroke
			(width 0)
			(type default)
		)
	)
	(wire
		(pts
			(xy 62.23 127) (xy 78.74 127)
		)
		(stroke
			(width 0)
			(type default)
		)
	)
	(wire
		(pts
			(xy 147.32 213.36) (xy 162.56 213.36)
		)
		(stroke
			(width 0)
			(type default)
		)
	)
	(bus
		(pts
			(xy 119.38 180.34) (xy 137.16 180.34)
		)
		(stroke
			(width 0)
			(type default)
			(color 255 153 0 1)
		)
	)
	(bus
		(pts
			(xy 248.92 172.72) (xy 266.7 172.72)
		)
		(stroke
			(width 0)
			(type default)
			(color 0 0 255 1)
		)
	)
	(bus
		(pts
			(xy 322.58 73.66) (xy 335.28 73.66)
		)
		(stroke
			(width 0)
			(type default)
		)
	)
	(wire
		(pts
			(xy 259.08 227.33) (xy 259.08 238.76)
		)
		(stroke
			(width 0)
			(type default)
		)
	)
	(wire
		(pts
			(xy 119.38 63.5) (xy 162.56 63.5)
		)
		(stroke
			(width 0)
			(type default)
		)
	)
	(wire
		(pts
			(xy 62.23 238.76) (xy 78.74 238.76)
		)
		(stroke
			(width 0)
			(type default)
		)
	)
	(wire
		(pts
			(xy 46.99 25.4) (xy 261.62 25.4)
		)
		(stroke
			(width 0)
			(type default)
		)
	)
	(wire
		(pts
			(xy 119.38 66.04) (xy 162.56 66.04)
		)
		(stroke
			(width 0)
			(type default)
		)
	)
	(wire
		(pts
			(xy 259.08 238.76) (xy 259.08 248.92)
		)
		(stroke
			(width 0)
			(type default)
		)
	)
	(wire
		(pts
			(xy 325.12 66.04) (xy 325.12 41.91)
		)
		(stroke
			(width 0)
			(type default)
		)
	)
	(wire
		(pts
			(xy 73.66 278.13) (xy 279.4 278.13)
		)
		(stroke
			(width 0)
			(type default)
		)
	)
	(wire
		(pts
			(xy 327.66 104.14) (xy 322.58 104.14)
		)
		(stroke
			(width 0)
			(type default)
		)
	)
	(bus
		(pts
			(xy 248.92 66.04) (xy 281.94 66.04)
		)
		(stroke
			(width 0)
			(type default)
			(color 194 0 194 1)
		)
	)
	(bus
		(pts
			(xy 254 58.42) (xy 254 35.56)
		)
		(stroke
			(width 0)
			(type default)
		)
	)
	(wire
		(pts
			(xy 55.88 68.58) (xy 78.74 68.58)
		)
		(stroke
			(width 0)
			(type default)
		)
	)
	(wire
		(pts
			(xy 147.32 248.92) (xy 147.32 213.36)
		)
		(stroke
			(width 0)
			(type default)
		)
	)
	(wire
		(pts
			(xy 162.56 210.82) (xy 144.78 210.82)
		)
		(stroke
			(width 0)
			(type default)
		)
	)
	(bus
		(pts
			(xy 119.38 124.46) (xy 162.56 124.46)
		)
		(stroke
			(width 0)
			(type default)
		)
	)
	(wire
		(pts
			(xy 363.22 22.86) (xy 299.72 22.86)
		)
		(stroke
			(width 0)
			(type default)
		)
	)
	(bus
		(pts
			(xy 248.92 219.71) (xy 266.7 219.71)
		)
		(stroke
			(width 0)
			(type default)
		)
	)
	(bus
		(pts
			(xy 67.31 208.28) (xy 142.24 208.28)
		)
		(stroke
			(width 0)
			(type default)
		)
	)
	(wire
		(pts
			(xy 121.92 127) (xy 162.56 127)
		)
		(stroke
			(width 0)
			(type default)
		)
	)
	(wire
		(pts
			(xy 68.58 215.9) (xy 68.58 259.08)
		)
		(stroke
			(width 0)
			(type default)
		)
	)
	(wire
		(pts
			(xy 325.12 101.6) (xy 325.12 66.04)
		)
		(stroke
			(width 0)
			(type default)
		)
	)
	(wire
		(pts
			(xy 322.58 71.12) (xy 332.74 71.12)
		)
		(stroke
			(width 0)
			(type default)
		)
	)
	(bus
		(pts
			(xy 273.05 171.45) (xy 281.94 171.45)
		)
		(stroke
			(width 0)
			(type default)
		)
	)
	(bus
		(pts
			(xy 44.45 22.86) (xy 261.62 22.86)
		)
		(stroke
			(width 0)
			(type default)
		)
	)
	(bus
		(pts
			(xy 254 35.56) (xy 261.62 35.56)
		)
		(stroke
			(width 0)
			(type default)
		)
	)
	(bus
		(pts
			(xy 119.38 121.92) (xy 162.56 121.92)
		)
		(stroke
			(width 0)
			(type default)
		)
	)
	(bus
		(pts
			(xy 78.74 129.54) (xy 76.2 129.54)
		)
		(stroke
			(width 0)
			(type default)
		)
	)
	(wire
		(pts
			(xy 66.04 218.44) (xy 78.74 218.44)
		)
		(stroke
			(width 0)
			(type default)
		)
	)
	(wire
		(pts
			(xy 363.22 213.36) (xy 363.22 22.86)
		)
		(stroke
			(width 0)
			(type default)
		)
	)
	(bus
		(pts
			(xy 256.54 246.38) (xy 256.54 241.3)
		)
		(stroke
			(width 0)
			(type default)
		)
	)
	(wire
		(pts
			(xy 78.74 215.9) (xy 68.58 215.9)
		)
		(stroke
			(width 0)
			(type default)
		)
	)
	(wire
		(pts
			(xy 254 254) (xy 274.32 254)
		)
		(stroke
			(width 0)
			(type default)
		)
	)
	(wire
		(pts
			(xy 76.2 275.59) (xy 276.86 275.59)
		)
		(stroke
			(width 0)
			(type default)
		)
	)
	(wire
		(pts
			(xy 259.08 248.92) (xy 254 248.92)
		)
		(stroke
			(width 0)
			(type default)
		)
	)
	(wire
		(pts
			(xy 254 251.46) (xy 261.62 251.46)
		)
		(stroke
			(width 0)
			(type default)
		)
	)
	(wire
		(pts
			(xy 355.6 27.94) (xy 299.72 27.94)
		)
		(stroke
			(width 0)
			(type default)
		)
	)
	(wire
		(pts
			(xy 76.2 233.68) (xy 78.74 233.68)
		)
		(stroke
			(width 0)
			(type default)
		)
	)
	(wire
		(pts
			(xy 78.74 220.98) (xy 71.12 220.98)
		)
		(stroke
			(width 0)
			(type default)
		)
	)
	(wire
		(pts
			(xy 119.38 88.9) (xy 121.92 88.9)
		)
		(stroke
			(width 0)
			(type default)
		)
	)
	(wire
		(pts
			(xy 62.23 269.24) (xy 62.23 238.76)
		)
		(stroke
			(width 0)
			(type default)
		)
	)
	(wire
		(pts
			(xy 205.74 246.38) (xy 205.74 238.76)
		)
		(stroke
			(width 0)
			(type default)
		)
	)
	(wire
		(pts
			(xy 270.51 168.91) (xy 248.92 168.91)
		)
		(stroke
			(width 0)
			(type default)
		)
	)
	(bus
		(pts
			(xy 264.16 208.28) (xy 281.94 208.28)
		)
		(stroke
			(width 0)
			(type default)
			(color 194 0 194 1)
		)
	)
	(wire
		(pts
			(xy 78.74 223.52) (xy 53.34 223.52)
		)
		(stroke
			(width 0)
			(type default)
		)
	)
	(wire
		(pts
			(xy 327.66 218.44) (xy 327.66 139.7)
		)
		(stroke
			(width 0)
			(type default)
		)
	)
	(bus
		(pts
			(xy 248.92 137.16) (xy 281.94 137.16)
		)
		(stroke
			(width 0)
			(type default)
			(color 194 0 194 1)
		)
	)
	(wire
		(pts
			(xy 332.74 220.98) (xy 322.58 220.98)
		)
		(stroke
			(width 0)
			(type default)
		)
	)
	(wire
		(pts
			(xy 144.78 210.82) (xy 144.78 251.46)
		)
		(stroke
			(width 0)
			(type default)
		)
	)
	(bus
		(pts
			(xy 119.38 106.68) (xy 162.56 106.68)
		)
		(stroke
			(width 0)
			(type default)
			(color 255 0 0 1)
		)
	)
	(wire
		(pts
			(xy 157.48 269.24) (xy 62.23 269.24)
		)
		(stroke
			(width 0)
			(type default)
		)
	)
	(bus
		(pts
			(xy 266.7 172.72) (xy 266.7 205.74)
		)
		(stroke
			(width 0)
			(type default)
			(color 0 0 255 1)
		)
	)
	(wire
		(pts
			(xy 46.99 149.86) (xy 78.74 149.86)
		)
		(stroke
			(width 0)
			(type default)
		)
	)
	(sheet
		(at 261.62 19.05)
		(size 38.1 25.4)
		(exclude_from_sim no)
		(in_bom yes)
		(on_board yes)
		(dnp no)
		(fields_autoplaced yes)
		(stroke
			(width 0.1524)
			(type solid)
		)
		(fill
			(color 0 0 0 0.0000)
		)
		(property "Sheetname" "PCIe misc"
			(at 261.62 18.3384 0)
			(effects
				(font
					(size 1.27 1.27)
				)
				(justify left bottom)
			)
		)
		(property "Sheetfile" "pcie_misc.kicad_sch"
			(at 261.62 45.0346 0)
			(effects
				(font
					(size 1.27 1.27)
				)
				(justify left top)
			)
		)
		(pin "PCIE_{REF2}{PCIe_{REF}}" output
			(at 299.72 25.4 0)
			(effects
				(font
					(size 1.27 1.27)
				)
				(justify right)
			)
		)
		(pin "PCIE_{REF4}{PCIe_{REF}}" output
			(at 299.72 20.32 0)
			(effects
				(font
					(size 1.27 1.27)
				)
				(justify right)
			)
		)
		(pin "PCIE_{REF3}{PCIe_{REF}}" output
			(at 261.62 22.86 180)
			(effects
				(font
					(size 1.27 1.27)
				)
				(justify left)
			)
		)
		(pin "PCIE_{REF0}{PCIe_{REF}}" output
			(at 299.72 35.56 0)
			(effects
				(font
					(size 1.27 1.27)
				)
				(justify right)
			)
		)
		(pin "PCIE_{REF1}{PCIe_{REF}}" output
			(at 299.72 30.48 0)
			(effects
				(font
					(size 1.27 1.27)
				)
				(justify right)
			)
		)
		(pin "PCIE_{REFIN}{PCIe_{REF}}" input
			(at 261.62 35.56 180)
			(effects
				(font
					(size 1.27 1.27)
				)
				(justify left)
			)
		)
		(pin "SUSCLK" output
			(at 299.72 41.91 0)
			(effects
				(font
					(size 1.27 1.27)
				)
				(justify right)
			)
		)
		(pin "~{CLKREQ0}" input
			(at 299.72 38.1 0)
			(effects
				(font
					(size 1.27 1.27)
				)
				(justify right)
			)
		)
		(pin "~{CLKREQ1}" input
			(at 299.72 33.02 0)
			(effects
				(font
					(size 1.27 1.27)
				)
				(justify right)
			)
		)
		(pin "~{CLKREQ2}" input
			(at 299.72 27.94 0)
			(effects
				(font
					(size 1.27 1.27)
				)
				(justify right)
			)
		)
		(pin "~{CLKREQ3}" input
			(at 261.62 25.4 180)
			(effects
				(font
					(size 1.27 1.27)
				)
				(justify left)
			)
		)
		(pin "~{CLKREQ4}" input
			(at 299.72 22.86 0)
			(effects
				(font
					(size 1.27 1.27)
				)
				(justify right)
			)
		)
		(instances
			(project "com-express-7-baseboard"
				(path ""
					(page "14")
				)
			)
		)
	)
	(sheet
		(at 281.94 60.96)
		(size 40.64 27.94)
		(exclude_from_sim no)
		(in_bom yes)
		(on_board yes)
		(dnp no)
		(fields_autoplaced yes)
		(stroke
			(width 0.1524)
			(type solid)
		)
		(fill
			(color 0 0 0 0.0000)
		)
		(property "Sheetname" "M.2 key M #1"
			(at 281.94 60.2484 0)
			(effects
				(font
					(size 1.27 1.27)
				)
				(justify left bottom)
			)
		)
		(property "Sheetfile" "m2keym_low.kicad_sch"
			(at 281.94 89.4846 0)
			(effects
				(font
					(size 1.27 1.27)
				)
				(justify left top)
			)
		)
		(pin "SUSCLK" input
			(at 322.58 66.04 0)
			(effects
				(font
					(size 1.27 1.27)
				)
				(justify right)
			)
		)
		(pin "PCIe_{x4}{PCIe}" input
			(at 281.94 66.04 180)
			(effects
				(font
					(size 1.27 1.27)
				)
				(justify left)
			)
		)
		(pin "~{PERST}" input
			(at 322.58 68.58 0)
			(effects
				(font
					(size 1.27 1.27)
				)
				(justify right)
			)
		)
		(pin "PCIE_{REF}{PCIe_{REF}}" input
			(at 322.58 73.66 0)
			(effects
				(font
					(size 1.27 1.27)
				)
				(justify right)
			)
		)
		(pin "~{CLKREQ}" output
			(at 322.58 71.12 0)
			(effects
				(font
					(size 1.27 1.27)
				)
				(justify right)
			)
		)
		(instances
			(project "com-express-7-baseboard"
				(path ""
					(page "8")
				)
			)
		)
	)
	(sheet
		(at 281.94 96.52)
		(size 40.64 27.94)
		(exclude_from_sim no)
		(in_bom yes)
		(on_board yes)
		(dnp no)
		(fields_autoplaced yes)
		(stroke
			(width 0.1524)
			(type solid)
		)
		(fill
			(color 0 0 0 0.0000)
		)
		(property "Sheetname" "M.2 key M #2"
			(at 281.94 95.8084 0)
			(effects
				(font
					(size 1.27 1.27)
				)
				(justify left bottom)
			)
		)
		(property "Sheetfile" "m2keym.kicad_sch"
			(at 281.94 125.0446 0)
			(effects
				(font
					(size 1.27 1.27)
				)
				(justify left top)
			)
		)
		(pin "SUSCLK" input
			(at 322.58 101.6 0)
			(effects
				(font
					(size 1.27 1.27)
				)
				(justify right)
			)
		)
		(pin "PCIe_{x4}{PCIe}" input
			(at 281.94 101.6 180)
			(effects
				(font
					(size 1.27 1.27)
				)
				(justify left)
			)
		)
		(pin "~{PERST}" input
			(at 322.58 104.14 0)
			(effects
				(font
					(size 1.27 1.27)
				)
				(justify right)
			)
		)
		(pin "PCIE_{REF}{PCIe_{REF}}" input
			(at 322.58 109.22 0)
			(effects
				(font
					(size 1.27 1.27)
				)
				(justify right)
			)
		)
		(pin "~{CLKREQ}" output
			(at 322.58 106.68 0)
			(effects
				(font
					(size 1.27 1.27)
				)
				(justify right)
			)
		)
		(instances
			(project "com-express-7-baseboard"
				(path ""
					(page "9")
				)
			)
		)
	)
	(sheet
		(at 78.74 175.26)
		(size 40.64 27.94)
		(exclude_from_sim no)
		(in_bom yes)
		(on_board yes)
		(dnp no)
		(fields_autoplaced yes)
		(stroke
			(width 0.1524)
			(type solid)
		)
		(fill
			(color 0 0 0 0.0000)
		)
		(property "Sheetname" "USB-C console"
			(at 78.74 174.5484 0)
			(effects
				(font
					(size 1.27 1.27)
				)
				(justify left bottom)
			)
		)
		(property "Sheetfile" "usb-c_console.kicad_sch"
			(at 78.74 203.7846 0)
			(effects
				(font
					(size 1.27 1.27)
				)
				(justify left top)
			)
		)
		(pin "UART_3V3{UART}" bidirectional
			(at 119.38 180.34 0)
			(effects
				(font
					(size 1.27 1.27)
				)
				(justify right)
			)
		)
		(instances
			(project "com-express-7-baseboard"
				(path ""
					(page "4")
				)
			)
		)
	)
	(sheet
		(at 78.74 213.36)
		(size 40.64 27.94)
		(exclude_from_sim no)
		(in_bom yes)
		(on_board yes)
		(dnp no)
		(fields_autoplaced yes)
		(stroke
			(width 0.1524)
			(type solid)
		)
		(fill
			(color 0 0 0 0.0000)
		)
		(property "Sheetname" "GPIO expander"
			(at 78.74 212.6484 0)
			(effects
				(font
					(size 1.27 1.27)
				)
				(justify left bottom)
			)
		)
		(property "Sheetfile" "gpio_exp.kicad_sch"
			(at 78.74 241.8846 0)
			(effects
				(font
					(size 1.27 1.27)
				)
				(justify left top)
			)
		)
		(pin "SMBus{I2C}" input
			(at 119.38 215.9 0)
			(effects
				(font
					(size 1.27 1.27)
				)
				(justify right)
			)
		)
		(pin "GPIOEX0" output
			(at 78.74 215.9 180)
			(effects
				(font
					(size 1.27 1.27)
				)
				(justify left)
			)
		)
		(pin "GPIOEX6" output
			(at 78.74 231.14 180)
			(effects
				(font
					(size 1.27 1.27)
				)
				(justify left)
			)
		)
		(pin "GPIOEX1" output
			(at 78.74 218.44 180)
			(effects
				(font
					(size 1.27 1.27)
				)
				(justify left)
			)
		)
		(pin "GPIOEX2" output
			(at 78.74 220.98 180)
			(effects
				(font
					(size 1.27 1.27)
				)
				(justify left)
			)
		)
		(pin "GPIOEX3" output
			(at 78.74 223.52 180)
			(effects
				(font
					(size 1.27 1.27)
				)
				(justify left)
			)
		)
		(pin "GPIOEX4" output
			(at 78.74 226.06 180)
			(effects
				(font
					(size 1.27 1.27)
				)
				(justify left)
			)
		)
		(pin "GPIOEX5" output
			(at 78.74 228.6 180)
			(effects
				(font
					(size 1.27 1.27)
				)
				(justify left)
			)
		)
		(pin "GPIOEX7" output
			(at 78.74 233.68 180)
			(effects
				(font
					(size 1.27 1.27)
				)
				(justify left)
			)
		)
		(pin "~{RESET}" input
			(at 78.74 238.76 180)
			(effects
				(font
					(size 1.27 1.27)
				)
				(justify left)
			)
		)
		(instances
			(project "com-express-7-baseboard"
				(path ""
					(page "16")
				)
			)
		)
	)
	(sheet
		(at 281.94 203.2)
		(size 40.64 27.94)
		(exclude_from_sim no)
		(in_bom yes)
		(on_board yes)
		(dnp no)
		(fields_autoplaced yes)
		(stroke
			(width 0.1524)
			(type solid)
		)
		(fill
			(color 0 0 0 0.0000)
		)
		(property "Sheetname" "Backplane"
			(at 281.94 202.4884 0)
			(effects
				(font
					(size 1.27 1.27)
				)
				(justify left bottom)
			)
		)
		(property "Sheetfile" "backplane.kicad_sch"
			(at 281.94 231.7246 0)
			(effects
				(font
					(size 1.27 1.27)
				)
				(justify left top)
			)
		)
		(pin "USB{USB}" input
			(at 281.94 205.74 180)
			(effects
				(font
					(size 1.27 1.27)
				)
				(justify left)
			)
		)
		(pin "UART{UART}" bidirectional
			(at 281.94 213.36 180)
			(effects
				(font
					(size 1.27 1.27)
				)
				(justify left)
			)
		)
		(pin "PCIe_{REF}{PCIe_{REF}}" input
			(at 322.58 215.9 0)
			(effects
				(font
					(size 1.27 1.27)
				)
				(justify right)
			)
		)
		(pin "PCIe_{x2}{PCIe}" input
			(at 281.94 208.28 180)
			(effects
				(font
					(size 1.27 1.27)
				)
				(justify left)
			)
		)
		(pin "~{PERST}" input
			(at 322.58 218.44 0)
			(effects
				(font
					(size 1.27 1.27)
				)
				(justify right)
			)
		)
		(pin "~{PRSNT}" output
			(at 322.58 213.36 0)
			(effects
				(font
					(size 1.27 1.27)
				)
				(justify right)
			)
		)
		(pin "GPIO" bidirectional
			(at 322.58 220.98 0)
			(effects
				(font
					(size 1.27 1.27)
				)
				(justify right)
			)
		)
		(instances
			(project "com-express-7-baseboard"
				(path ""
					(page "6")
				)
			)
		)
	)
	(sheet
		(at 157.48 243.84)
		(size 40.64 27.94)
		(exclude_from_sim no)
		(in_bom yes)
		(on_board yes)
		(dnp no)
		(fields_autoplaced yes)
		(stroke
			(width 0.1524)
			(type solid)
		)
		(fill
			(color 0 0 0 0.0000)
		)
		(property "Sheetname" "Misc"
			(at 157.48 243.1284 0)
			(effects
				(font
					(size 1.27 1.27)
				)
				(justify left bottom)
			)
		)
		(property "Sheetfile" "misc.kicad_sch"
			(at 157.48 272.3646 0)
			(effects
				(font
					(size 1.27 1.27)
				)
				(justify left top)
			)
		)
		(pin "TACH_{CPUFAN}" output
			(at 157.48 251.46 180)
			(effects
				(font
					(size 1.27 1.27)
				)
				(justify left)
			)
		)
		(pin "PWM_{CPUFAN}" input
			(at 157.48 248.92 180)
			(effects
				(font
					(size 1.27 1.27)
				)
				(justify left)
			)
		)
		(pin "SMBus{I2C}" input
			(at 157.48 246.38 180)
			(effects
				(font
					(size 1.27 1.27)
				)
				(justify left)
			)
		)
		(pin "LED_G" input
			(at 157.48 259.08 180)
			(effects
				(font
					(size 1.27 1.27)
				)
				(justify left)
			)
		)
		(pin "LED_B" input
			(at 157.48 261.62 180)
			(effects
				(font
					(size 1.27 1.27)
				)
				(justify left)
			)
		)
		(pin "LED_R" input
			(at 157.48 256.54 180)
			(effects
				(font
					(size 1.27 1.27)
				)
				(justify left)
			)
		)
		(pin "~{RESET}" input
			(at 157.48 269.24 180)
			(effects
				(font
					(size 1.27 1.27)
				)
				(justify left)
			)
		)
		(pin "PWR_OK" input
			(at 198.12 246.38 0)
			(effects
				(font
					(size 1.27 1.27)
				)
				(justify right)
			)
		)
		(instances
			(project "com-express-7-baseboard"
				(path ""
					(page "11")
				)
			)
		)
	)
	(sheet
		(at 281.94 167.64)
		(size 40.64 27.94)
		(exclude_from_sim no)
		(in_bom yes)
		(on_board yes)
		(dnp no)
		(fields_autoplaced yes)
		(stroke
			(width 0.1524)
			(type solid)
		)
		(fill
			(color 0 0 0 0.0000)
		)
		(property "Sheetname" "SD card"
			(at 281.94 166.9284 0)
			(effects
				(font
					(size 1.27 1.27)
				)
				(justify left bottom)
			)
		)
		(property "Sheetfile" "sd_card.kicad_sch"
			(at 281.94 196.1646 0)
			(effects
				(font
					(size 1.27 1.27)
				)
				(justify left top)
			)
		)
		(pin "CD_SW" output
			(at 281.94 173.99 180)
			(effects
				(font
					(size 1.27 1.27)
				)
				(justify left)
			)
		)
		(pin "SDIO{SDIO}" input
			(at 281.94 171.45 180)
			(effects
				(font
					(size 1.27 1.27)
				)
				(justify left)
			)
		)
		(instances
			(project "com-express-7-baseboard"
				(path ""
					(page "19")
				)
			)
		)
	)
	(sheet
		(at 127 139.7)
		(size 27.94 27.94)
		(exclude_from_sim no)
		(in_bom yes)
		(on_board yes)
		(dnp no)
		(fields_autoplaced yes)
		(stroke
			(width 0.1524)
			(type solid)
		)
		(fill
			(color 0 0 0 0.0000)
		)
		(property "Sheetname" "PCIe redriver"
			(at 127 138.9884 0)
			(effects
				(font
					(size 1.27 1.27)
				)
				(justify left bottom)
			)
		)
		(property "Sheetfile" "pcie_redriver.kicad_sch"
			(at 127 168.2246 0)
			(effects
				(font
					(size 1.27 1.27)
				)
				(justify left top)
			)
		)
		(pin "PCIe_{I}{PCIe}" input
			(at 154.94 144.78 0)
			(effects
				(font
					(size 1.27 1.27)
				)
				(justify right)
			)
		)
		(pin "PCIe_{O}{PCIe}" output
			(at 127 144.78 180)
			(effects
				(font
					(size 1.27 1.27)
				)
				(justify left)
			)
		)
		(pin "~{PRSNT}" input
			(at 127 165.1 180)
			(effects
				(font
					(size 1.27 1.27)
				)
				(justify left)
			)
		)
		(instances
			(project "com-express-7-baseboard"
				(path ""
					(page "15")
				)
			)
		)
	)
	(sheet
		(at 213.36 243.84)
		(size 40.64 27.94)
		(exclude_from_sim no)
		(in_bom yes)
		(on_board yes)
		(dnp no)
		(fields_autoplaced yes)
		(stroke
			(width 0.1524)
			(type solid)
		)
		(fill
			(color 0 0 0 0.0000)
		)
		(property "Sheetname" "Power"
			(at 213.36 243.1284 0)
			(effects
				(font
					(size 1.27 1.27)
				)
				(justify left bottom)
			)
		)
		(property "Sheetfile" "power.kicad_sch"
			(at 213.36 272.3646 0)
			(effects
				(font
					(size 1.27 1.27)
				)
				(justify left top)
			)
		)
		(pin "PWR_OK" output
			(at 254 248.92 0)
			(effects
				(font
					(size 1.27 1.27)
				)
				(justify right)
			)
		)
		(pin "PSON" input
			(at 254 251.46 0)
			(effects
				(font
					(size 1.27 1.27)
				)
				(justify right)
			)
		)
		(pin "~{RESET}" input
			(at 254 254 0)
			(effects
				(font
					(size 1.27 1.27)
				)
				(justify right)
			)
		)
		(pin "I2C{I2C}" input
			(at 254 246.38 0)
			(effects
				(font
					(size 1.27 1.27)
				)
				(justify right)
			)
		)
		(instances
			(project "com-express-7-baseboard"
				(path ""
					(page "7")
				)
			)
		)
	)
	(sheet
		(at 78.74 139.7)
		(size 40.64 27.94)
		(exclude_from_sim no)
		(in_bom yes)
		(on_board yes)
		(dnp no)
		(fields_autoplaced yes)
		(stroke
			(width 0.1524)
			(type solid)
		)
		(fill
			(color 0 0 0 0.0000)
		)
		(property "Sheetname" "OCuLink"
			(at 78.74 138.9884 0)
			(effects
				(font
					(size 1.27 1.27)
				)
				(justify left bottom)
			)
		)
		(property "Sheetfile" "oculink.kicad_sch"
			(at 78.74 168.2246 0)
			(effects
				(font
					(size 1.27 1.27)
				)
				(justify left top)
			)
		)
		(pin "~{PERST}" input
			(at 78.74 144.78 180)
			(effects
				(font
					(size 1.27 1.27)
				)
				(justify left)
			)
		)
		(pin "PCIe_{REF0}{PCIe_{REF}}" input
			(at 78.74 147.32 180)
			(effects
				(font
					(size 1.27 1.27)
				)
				(justify left)
			)
		)
		(pin "PCIe_{x4}{PCIe}" input
			(at 119.38 144.78 0)
			(effects
				(font
					(size 1.27 1.27)
				)
				(justify right)
			)
		)
		(pin "~{CPRSNT0}" output
			(at 78.74 149.86 180)
			(effects
				(font
					(size 1.27 1.27)
				)
				(justify left)
			)
		)
		(pin "I2C0{I2C}" input
			(at 78.74 152.4 180)
			(effects
				(font
					(size 1.27 1.27)
				)
				(justify left)
			)
		)
		(instances
			(project "com-express-7-baseboard"
				(path ""
					(page "5")
				)
			)
		)
	)
	(sheet
		(at 78.74 104.14)
		(size 40.64 27.94)
		(exclude_from_sim no)
		(in_bom yes)
		(on_board yes)
		(dnp no)
		(fields_autoplaced yes)
		(stroke
			(width 0.1524)
			(type solid)
		)
		(fill
			(color 0 0 0 0.0000)
		)
		(property "Sheetname" "2xSFP+"
			(at 78.74 103.4284 0)
			(effects
				(font
					(size 1.27 1.27)
				)
				(justify left bottom)
			)
		)
		(property "Sheetfile" "2xSFP+.kicad_sch"
			(at 78.74 132.6646 0)
			(effects
				(font
					(size 1.27 1.27)
				)
				(justify left top)
			)
		)
		(pin "I2C_{SFP0}{I2C}" input
			(at 119.38 116.84 0)
			(effects
				(font
					(size 1.27 1.27)
				)
				(justify right)
			)
		)
		(pin "10GKR_SFP0{10GBaseKR}" input
			(at 119.38 106.68 0)
			(effects
				(font
					(size 1.27 1.27)
				)
				(justify right)
			)
		)
		(pin "MOD0_ABS" output
			(at 119.38 111.76 0)
			(effects
				(font
					(size 1.27 1.27)
				)
				(justify right)
			)
		)
		(pin "MDIO0{MDIO}" input
			(at 119.38 121.92 0)
			(effects
				(font
					(size 1.27 1.27)
				)
				(justify right)
			)
		)
		(pin "PHY0_{RESET}" input
			(at 119.38 127 0)
			(effects
				(font
					(size 1.27 1.27)
				)
				(justify right)
			)
		)
		(pin "I2C_{SFP1}{I2C}" input
			(at 119.38 119.38 0)
			(effects
				(font
					(size 1.27 1.27)
				)
				(justify right)
			)
		)
		(pin "10GKR_SFP1{10GBaseKR}" input
			(at 119.38 109.22 0)
			(effects
				(font
					(size 1.27 1.27)
				)
				(justify right)
			)
		)
		(pin "MOD1_ABS" output
			(at 119.38 114.3 0)
			(effects
				(font
					(size 1.27 1.27)
				)
				(justify right)
			)
		)
		(pin "PHY1_{RESET}" input
			(at 119.38 129.54 0)
			(effects
				(font
					(size 1.27 1.27)
				)
				(justify right)
			)
		)
		(pin "MDIO1{MDIO}" input
			(at 119.38 124.46 0)
			(effects
				(font
					(size 1.27 1.27)
				)
				(justify right)
			)
		)
		(pin "I2C_{LED}{I2C}" input
			(at 78.74 129.54 180)
			(effects
				(font
					(size 1.27 1.27)
				)
				(justify left)
			)
		)
		(pin "~{RESET}" input
			(at 78.74 127 180)
			(effects
				(font
					(size 1.27 1.27)
				)
				(justify left)
			)
		)
		(instances
			(project "com-express-7-baseboard"
				(path ""
					(page "3")
				)
			)
		)
	)
	(sheet
		(at 162.56 53.34)
		(size 86.36 132.08)
		(exclude_from_sim no)
		(in_bom yes)
		(on_board yes)
		(dnp no)
		(fields_autoplaced yes)
		(stroke
			(width 0.1524)
			(type solid)
		)
		(fill
			(color 0 0 0 0.0000)
		)
		(property "Sheetname" "Com Express 7 Interfaces"
			(at 162.56 52.6284 0)
			(effects
				(font
					(size 1.27 1.27)
				)
				(justify left bottom)
			)
		)
		(property "Sheetfile" "com_express_7_interfaces.kicad_sch"
			(at 162.56 186.0046 0)
			(effects
				(font
					(size 1.27 1.27)
				)
				(justify left top)
			)
		)
		(pin "PCIe_{B1x4}{PCIe}" output
			(at 162.56 144.78 180)
			(effects
				(font
					(size 1.27 1.27)
				)
				(justify left)
			)
		)
		(pin "PCIe_{B1x2}{PCIe}" output
			(at 248.92 137.16 0)
			(effects
				(font
					(size 1.27 1.27)
				)
				(justify right)
			)
		)
		(pin "USB0{USB}" output
			(at 248.92 172.72 0)
			(effects
				(font
					(size 1.27 1.27)
				)
				(justify right)
			)
		)
		(pin "KR0{10GBaseKR}" output
			(at 162.56 106.68 180)
			(effects
				(font
					(size 1.27 1.27)
				)
				(justify left)
			)
		)
		(pin "KR1{10GBaseKR}" output
			(at 162.56 109.22 180)
			(effects
				(font
					(size 1.27 1.27)
				)
				(justify left)
			)
		)
		(pin "PCIe_{B3x2}{PCIe}" output
			(at 248.92 180.34 0)
			(effects
				(font
					(size 1.27 1.27)
				)
				(justify right)
			)
		)
		(pin "GBE0{GbE}" output
			(at 162.56 60.96 180)
			(effects
				(font
					(size 1.27 1.27)
				)
				(justify left)
			)
		)
		(pin "PCIE_{REF}{PCIe_{REF}}" output
			(at 248.92 58.42 0)
			(effects
				(font
					(size 1.27 1.27)
				)
				(justify right)
			)
		)
		(pin "USB3{USB}" output
			(at 162.56 81.28 180)
			(effects
				(font
					(size 1.27 1.27)
				)
				(justify left)
			)
		)
		(pin "USB2{USB}" output
			(at 162.56 73.66 180)
			(effects
				(font
					(size 1.27 1.27)
				)
				(justify left)
			)
		)
		(pin "USB1{USB}" output
			(at 248.92 142.24 0)
			(effects
				(font
					(size 1.27 1.27)
				)
				(justify right)
			)
		)
		(pin "USBSS3{USBSS}" output
			(at 162.56 83.82 180)
			(effects
				(font
					(size 1.27 1.27)
				)
				(justify left)
			)
		)
		(pin "USBSS2{USBSS}" output
			(at 162.56 76.2 180)
			(effects
				(font
					(size 1.27 1.27)
				)
				(justify left)
			)
		)
		(pin "~{GBE0_ACT}" output
			(at 162.56 68.58 180)
			(effects
				(font
					(size 1.27 1.27)
				)
				(justify left)
			)
		)
		(pin "~{GBE0_LINK_1000}" output
			(at 162.56 63.5 180)
			(effects
				(font
					(size 1.27 1.27)
				)
				(justify left)
			)
		)
		(pin "PCIe_{B2Ax4}{PCIe}" output
			(at 248.92 101.6 0)
			(effects
				(font
					(size 1.27 1.27)
				)
				(justify right)
			)
		)
		(pin "PCIe_{B2Bx4}{PCIe}" output
			(at 248.92 66.04 0)
			(effects
				(font
					(size 1.27 1.27)
				)
				(justify right)
			)
		)
		(pin "~{USB_2_3_OC}" input
			(at 162.56 86.36 180)
			(effects
				(font
					(size 1.27 1.27)
				)
				(justify left)
			)
		)
		(pin "~{GBE0_LINK}" output
			(at 162.56 66.04 180)
			(effects
				(font
					(size 1.27 1.27)
				)
				(justify left)
			)
		)
		(pin "10G_INT0" input
			(at 162.56 111.76 180)
			(effects
				(font
					(size 1.27 1.27)
				)
				(justify left)
			)
		)
		(pin "10G_INT1" input
			(at 162.56 114.3 180)
			(effects
				(font
					(size 1.27 1.27)
				)
				(justify left)
			)
		)
		(pin "I2C_{10GLED}{I2C}" output
			(at 162.56 135.89 180)
			(effects
				(font
					(size 1.27 1.27)
				)
				(justify left)
			)
		)
		(pin "I2C_{SFP1}{I2C}" output
			(at 162.56 119.38 180)
			(effects
				(font
					(size 1.27 1.27)
				)
				(justify left)
			)
		)
		(pin "I2C_{SFP0}{I2C}" output
			(at 162.56 116.84 180)
			(effects
				(font
					(size 1.27 1.27)
				)
				(justify left)
			)
		)
		(pin "MDIO1{MDIO}" output
			(at 162.56 124.46 180)
			(effects
				(font
					(size 1.27 1.27)
				)
				(justify left)
			)
		)
		(pin "MDIO0{MDIO}" output
			(at 162.56 121.92 180)
			(effects
				(font
					(size 1.27 1.27)
				)
				(justify left)
			)
		)
		(pin "10G_PHY_RST01" output
			(at 162.56 127 180)
			(effects
				(font
					(size 1.27 1.27)
				)
				(justify left)
			)
		)
		(pin "SDIO{SDIO}" output
			(at 248.92 166.37 0)
			(effects
				(font
					(size 1.27 1.27)
				)
				(justify right)
			)
		)
		(pin "SD_CD" input
			(at 248.92 168.91 0)
			(effects
				(font
					(size 1.27 1.27)
				)
				(justify right)
			)
		)
		(instances
			(project "com-express-7-baseboard"
				(path ""
					(page "12")
				)
			)
		)
	)
	(sheet
		(at 78.74 58.42)
		(size 40.64 33.02)
		(exclude_from_sim no)
		(in_bom yes)
		(on_board yes)
		(dnp no)
		(fields_autoplaced yes)
		(stroke
			(width 0.1524)
			(type solid)
		)
		(fill
			(color 0 0 0 0.0000)
		)
		(property "Sheetname" "2xUSB3.0+RJ45"
			(at 78.74 57.7084 0)
			(effects
				(font
					(size 1.27 1.27)
				)
				(justify left bottom)
			)
		)
		(property "Sheetfile" "usb3+rj45.kicad_sch"
			(at 78.74 92.0246 0)
			(effects
				(font
					(size 1.27 1.27)
				)
				(justify left top)
			)
		)
		(pin "GbE{GbE}" input
			(at 119.38 60.96 0)
			(effects
				(font
					(size 1.27 1.27)
				)
				(justify right)
			)
		)
		(pin "EN_1" input
			(at 78.74 66.04 180)
			(effects
				(font
					(size 1.27 1.27)
				)
				(justify left)
			)
		)
		(pin "FLG_1" output
			(at 119.38 86.36 0)
			(effects
				(font
					(size 1.27 1.27)
				)
				(justify right)
			)
		)
		(pin "USB_1{USB}" input
			(at 119.38 73.66 0)
			(effects
				(font
					(size 1.27 1.27)
				)
				(justify right)
			)
		)
		(pin "USBSS_1{USBSS}" input
			(at 119.38 76.2 0)
			(effects
				(font
					(size 1.27 1.27)
				)
				(justify right)
			)
		)
		(pin "USB_2{USB}" input
			(at 119.38 81.28 0)
			(effects
				(font
					(size 1.27 1.27)
				)
				(justify right)
			)
		)
		(pin "USBSS_2{USBSS}" input
			(at 119.38 83.82 0)
			(effects
				(font
					(size 1.27 1.27)
				)
				(justify right)
			)
		)
		(pin "EN_2" input
			(at 78.74 68.58 180)
			(effects
				(font
					(size 1.27 1.27)
				)
				(justify left)
			)
		)
		(pin "FLG_2" output
			(at 119.38 88.9 0)
			(effects
				(font
					(size 1.27 1.27)
				)
				(justify right)
			)
		)
		(pin "~{GBE0_LINK_1000}" input
			(at 119.38 63.5 0)
			(effects
				(font
					(size 1.27 1.27)
				)
				(justify right)
			)
		)
		(pin "~{GBE0_ACT}" input
			(at 119.38 68.58 0)
			(effects
				(font
					(size 1.27 1.27)
				)
				(justify right)
			)
		)
		(pin "~{GBE0_LINK}" input
			(at 119.38 66.04 0)
			(effects
				(font
					(size 1.27 1.27)
				)
				(justify right)
			)
		)
		(instances
			(project "com-express-7-baseboard"
				(path ""
					(page "2")
				)
			)
		)
	)
	(sheet
		(at 281.94 132.08)
		(size 40.64 27.94)
		(exclude_from_sim no)
		(in_bom yes)
		(on_board yes)
		(dnp no)
		(fields_autoplaced yes)
		(stroke
			(width 0.1524)
			(type solid)
		)
		(fill
			(color 0 0 0 0.0000)
		)
		(property "Sheetname" "M.2 key E"
			(at 281.94 131.3684 0)
			(effects
				(font
					(size 1.27 1.27)
				)
				(justify left bottom)
			)
		)
		(property "Sheetfile" "m2keye.kicad_sch"
			(at 281.94 160.6046 0)
			(effects
				(font
					(size 1.27 1.27)
				)
				(justify left top)
			)
		)
		(pin "USB{USB}" input
			(at 281.94 142.24 180)
			(effects
				(font
					(size 1.27 1.27)
				)
				(justify left)
			)
		)
		(pin "SUSCLK" input
			(at 322.58 137.16 0)
			(effects
				(font
					(size 1.27 1.27)
				)
				(justify right)
			)
		)
		(pin "PCIe_{x1}{PCIe}" input
			(at 281.94 137.16 180)
			(effects
				(font
					(size 1.27 1.27)
				)
				(justify left)
			)
		)
		(pin "~{PERST}" input
			(at 322.58 139.7 0)
			(effects
				(font
					(size 1.27 1.27)
				)
				(justify right)
			)
		)
		(pin "PCIE_{REF}{PCIe_{REF}}" input
			(at 322.58 144.78 0)
			(effects
				(font
					(size 1.27 1.27)
				)
				(justify right)
			)
		)
		(pin "~{CLKREQ}" output
			(at 322.58 142.24 0)
			(effects
				(font
					(size 1.27 1.27)
				)
				(justify right)
			)
		)
		(instances
			(project "com-express-7-baseboard"
				(path ""
					(page "10")
				)
			)
		)
	)
	(sheet
		(at 162.56 193.04)
		(size 86.36 38.1)
		(exclude_from_sim no)
		(in_bom yes)
		(on_board yes)
		(dnp no)
		(fields_autoplaced yes)
		(stroke
			(width 0.1524)
			(type solid)
		)
		(fill
			(color 0 0 0 0.0000)
		)
		(property "Sheetname" "Com Express 7 MGMT"
			(at 162.56 192.3284 0)
			(effects
				(font
					(size 1.27 1.27)
				)
				(justify left bottom)
			)
		)
		(property "Sheetfile" "com_express_7_mgmt.kicad_sch"
			(at 162.56 231.7246 0)
			(effects
				(font
					(size 1.27 1.27)
				)
				(justify left top)
			)
		)
		(pin "SMBus{I2C}" output
			(at 162.56 208.28 180)
			(effects
				(font
					(size 1.27 1.27)
				)
				(justify left)
			)
		)
		(pin "FAN_PWM" output
			(at 162.56 213.36 180)
			(effects
				(font
					(size 1.27 1.27)
				)
				(justify left)
			)
		)
		(pin "FAM_TACH" input
			(at 162.56 210.82 180)
			(effects
				(font
					(size 1.27 1.27)
				)
				(justify left)
			)
		)
		(pin "~{CB_RESET}" output
			(at 248.92 222.25 0)
			(effects
				(font
					(size 1.27 1.27)
				)
				(justify right)
			)
		)
		(pin "PWR_OK" input
			(at 248.92 227.33 0)
			(effects
				(font
					(size 1.27 1.27)
				)
				(justify right)
			)
		)
		(pin "SER0{UART}" bidirectional
			(at 162.56 195.58 180)
			(effects
				(font
					(size 1.27 1.27)
				)
				(justify left)
			)
		)
		(pin "SER1{UART}" bidirectional
			(at 248.92 195.58 0)
			(effects
				(font
					(size 1.27 1.27)
				)
				(justify right)
			)
		)
		(pin "PSON" output
			(at 248.92 224.79 0)
			(effects
				(font
					(size 1.27 1.27)
				)
				(justify right)
			)
		)
		(pin "I2C{I2C}" output
			(at 248.92 219.71 0)
			(effects
				(font
					(size 1.27 1.27)
				)
				(justify right)
			)
		)
		(instances
			(project "com-express-7-baseboard"
				(path ""
					(page "13")
				)
			)
		)
	)
	(sheet_instances
		(path "/"
			(page "1")
		)
	)
)
